# S9S_MB_2U (Grand Teton) — schematic netlist excerpt (pin names and nets, part order shuffled) for the footprints in the layout excerpt that follows; sources: Cadence DE-HDL packaged netlist, KiCad conversion of 03242023_DA0F0TMBIJ0_F0T_Motherboard_J_brd_V01_OCP.brd

PC1226  Q_CAP  47UF 4V 20% X6S  pkg C0805  page 262 : A = P1V05_PCH_AUX ; B = GND
PC1206_P1_3  Q_CAP  22UF 4V 20% X6S  pkg C0805  page 290 : A = PVCCFA_EHV_FIVRA_CPU1 ; B = GND
PR4265  Q_RES  499 1% CHIP  pkg 0402LF  page 271 : A = PVCCFA_EHV_FIVRA_CPU0 ; B = GND

(kicad_pcb
	(version 20260206)
	(generator "pcbnew")
	(generator_version "10.0")
	(general
		(thickness 1.6)
		(legacy_teardrops no)
	)
	(paper "A4")
	(title_block
		(title "03242023_DA0F0TMBIJ0_F0T_Motherboard_J_brd_V01_OCP.brd")
		(comment 1 "Grand Teton / footprints 4788-4790 of 6105")
	)
	(layers
		(0 "F.Cu" signal "TOP")
		(4 "In1.Cu" signal "GND")
		(6 "In2.Cu" signal "IN1")
		(8 "In3.Cu" signal "GND1")
		(10 "In4.Cu" signal "IN2")
		(12 "In5.Cu" signal "GND2")
		(14 "In6.Cu" signal "IN3")
		(16 "In7.Cu" signal "GND3")
		(18 "In8.Cu" signal "VCC")
		(20 "In9.Cu" signal "VCC1")
		(22 "In10.Cu" signal "GND4")
		(24 "In11.Cu" signal "IN4")
		(26 "In12.Cu" signal "GND5")
		(28 "In13.Cu" signal "IN5")
		(30 "In14.Cu" signal "GND6")
		(32 "In15.Cu" signal "IN6")
		(34 "In16.Cu" signal "GND7")
		(2 "B.Cu" signal "BOTTOM")
		(9 "F.Adhes" user "F.Adhesive")
		(11 "B.Adhes" user "B.Adhesive")
		(13 "F.Paste" user "Package Geometry/Pastemask Top")
		(15 "B.Paste" user "Package Geometry/Pastemask Bottom")
		(5 "F.SilkS" user "Ref Des/Silkscreen Top")
		(7 "B.SilkS" user "Ref Des/Silkscreen Bottom")
		(1 "F.Mask" user "Board Geometry/Soldermask Top")
		(3 "B.Mask" user "Board Geometry/Soldermask Bottom")
		(17 "Dwgs.User" user "User.Drawings")
		(19 "Cmts.User" user "User.Comments")
		(21 "Eco1.User" user "User.Eco1")
		(23 "Eco2.User" user "User.Eco2")
		(25 "Edge.Cuts" user "Board Geometry/Outline")
		(27 "Margin" user)
		(31 "F.CrtYd" user "Package Geometry/Place Bound Top")
		(29 "B.CrtYd" user "Package Geometry/Place Bound Bottom")
		(35 "F.Fab" user "Ref Des/Assembly Top")
		(33 "B.Fab" user "Ref Des/Assembly Bottom")
	)
	(footprint ""
		(layer "B.Cu")
		(at 283.82468 -354.028502 -90)
		(property "Reference" "PR4265"
			(at 0 0 90)
			(layer "B.SilkS")
			(hide yes)
			(effects
				(font
					(size 1.27 1.27)
				)
				(justify mirror)
			)
		)
		(property "Value" ""
			(at 0 0 90)
			(layer "B.Fab")
			(effects
				(font
					(size 1.27 1.27)
				)
				(justify mirror)
			)
		)
		(duplicate_pad_numbers_are_jumpers no)
		(fp_line
			(start -0.7874 0.4064)
			(end 0.7874 0.4064)
			(stroke
				(width 0.1524)
				(type default)
			)
			(layer "B.SilkS")
		)
		(fp_line
			(start 0.7874 0.4064)
			(end 0.7874 -0.4064)
			(stroke
				(width 0.1524)
				(type default)
			)
			(layer "B.SilkS")
		)
		(fp_line
			(start -0.7874 -0.4064)
			(end -0.7874 0.4064)
			(stroke
				(width 0.1524)
				(type default)
			)
			(layer "B.SilkS")
		)
		(fp_line
			(start 0.7874 -0.4064)
			(end -0.7874 -0.4064)
			(stroke
				(width 0.1524)
				(type default)
			)
			(layer "B.SilkS")
		)
		(fp_line
			(start -0.67945 0.3048)
			(end -0.120396 0.3048)
			(stroke
				(width 0.1)
				(type default)
			)
			(layer "B.Fab")
		)
		(fp_line
			(start -0.120396 0.3048)
			(end -0.120396 0.2794)
			(stroke
				(width 0.1)
				(type default)
			)
			(layer "B.Fab")
		)
		(fp_line
			(start 0.12065 0.3048)
			(end 0.67945 0.3048)
			(stroke
				(width 0.1)
				(type default)
			)
			(layer "B.Fab")
		)
		(fp_line
			(start 0.67945 0.3048)
			(end 0.67945 -0.305054)
			(stroke
				(width 0.1)
				(type default)
			)
			(layer "B.Fab")
		)
		(fp_line
			(start -0.120396 0.2794)
			(end 0.12065 0.2794)
			(stroke
				(width 0.1)
				(type default)
			)
			(layer "B.Fab")
		)
		(fp_line
			(start 0.12065 0.2794)
			(end 0.12065 0.3048)
			(stroke
				(width 0.1)
				(type default)
			)
			(layer "B.Fab")
		)
		(fp_line
			(start -0.12065 -0.2794)
			(end -0.12065 -0.3048)
			(stroke
				(width 0.1)
				(type default)
			)
			(layer "B.Fab")
		)
		(fp_line
			(start 0.12065 -0.2794)
			(end -0.12065 -0.2794)
			(stroke
				(width 0.1)
				(type default)
			)
			(layer "B.Fab")
		)
		(fp_line
			(start -0.67945 -0.3048)
			(end -0.67945 0.3048)
			(stroke
				(width 0.1)
				(type default)
			)
			(layer "B.Fab")
		)
		(fp_line
			(start -0.12065 -0.3048)
			(end -0.67945 -0.3048)
			(stroke
				(width 0.1)
				(type default)
			)
			(layer "B.Fab")
		)
		(fp_line
			(start 0.12065 -0.305054)
			(end 0.12065 -0.2794)
			(stroke
				(width 0.1)
				(type default)
			)
			(layer "B.Fab")
		)
		(fp_line
			(start 0.67945 -0.305054)
			(end 0.12065 -0.305054)
			(stroke
				(width 0.1)
				(type default)
			)
			(layer "B.Fab")
		)
		(pad "1" smd circle
			(at 0.40005 0 90)
			(size 0 0)
			(layers "B.Cu" "B.Mask" "B.Paste")
			(net "PVCCFA_EHV_FIVRA_CPU0")
		)
		(pad "2" smd circle
			(at -0.40005 0 90)
			(size 0 0)
			(layers "B.Cu" "B.Mask" "B.Paste")
			(net "GND")
		)
	)
	(footprint ""
		(layer "B.Cu")
		(at 272.444972 -68.4784)
		(property "Reference" "PC1226"
			(at 0 0 0)
			(layer "B.SilkS")
			(hide yes)
			(effects
				(font
					(size 1.27 1.27)
				)
				(justify mirror)
			)
		)
		(property "Value" ""
			(at 0 0 0)
			(layer "B.Fab")
			(effects
				(font
					(size 1.27 1.27)
				)
				(justify mirror)
			)
		)
		(duplicate_pad_numbers_are_jumpers no)
		(fp_line
			(start -1.524 -0.762)
			(end -1.524 0.762)
			(stroke
				(width 0.1524)
				(type default)
			)
			(layer "B.SilkS")
		)
		(fp_line
			(start -1.524 0.762)
			(end 1.524 0.762)
			(stroke
				(width 0.1524)
				(type default)
			)
			(layer "B.SilkS")
		)
		(fp_line
			(start 1.524 -0.762)
			(end -1.524 -0.762)
			(stroke
				(width 0.1524)
				(type default)
			)
			(layer "B.SilkS")
		)
		(fp_line
			(start 1.524 0.762)
			(end 1.524 -0.762)
			(stroke
				(width 0.1524)
				(type default)
			)
			(layer "B.SilkS")
		)
		(fp_line
			(start -1.1049 -0.724916)
			(end 1.1049 -0.724916)
			(stroke
				(width 0.1)
				(type default)
			)
			(layer "B.Fab")
		)
		(fp_line
			(start -1.1049 0.724916)
			(end -1.1049 -0.724916)
			(stroke
				(width 0.1)
				(type default)
			)
			(layer "B.Fab")
		)
		(fp_line
			(start 1.1049 -0.724916)
			(end 1.1049 0.724916)
			(stroke
				(width 0.1)
				(type default)
			)
			(layer "B.Fab")
		)
		(fp_line
			(start 1.1049 0.724916)
			(end -1.1049 0.724916)
			(stroke
				(width 0.1)
				(type default)
			)
			(layer "B.Fab")
		)
		(pad "1" smd rect
			(at 0.889 0)
			(size 1.016 1.27)
			(layers "B.Cu" "B.Mask" "B.Paste")
			(net "P1V05_PCH_AUX")
		)
		(pad "2" smd rect
			(at -0.889 0)
			(size 1.016 1.27)
			(layers "B.Cu" "B.Mask" "B.Paste")
			(net "GND")
		)
	)
	(footprint ""
		(layer "B.Cu")
		(at 186.331352 -344.656664 -90)
		(property "Reference" "PC1206_P1_3"
			(at 0 0 90)
			(layer "B.SilkS")
			(hide yes)
			(effects
				(font
					(size 1.27 1.27)
				)
				(justify mirror)
			)
		)
		(property "Value" ""
			(at 0 0 90)
			(layer "B.Fab")
			(effects
				(font
					(size 1.27 1.27)
				)
				(justify mirror)
			)
		)
		(duplicate_pad_numbers_are_jumpers no)
		(fp_line
			(start -1.524 0.762)
			(end 1.524 0.762)
			(stroke
				(width 0.1524)
				(type default)
			)
			(layer "B.SilkS")
		)
		(fp_line
			(start 1.524 0.762)
			(end 1.524 -0.762)
			(stroke
				(width 0.1524)
				(type default)
			)
			(layer "B.SilkS")
		)
		(fp_line
			(start -1.524 -0.762)
			(end -1.524 0.762)
			(stroke
				(width 0.1524)
				(type default)
			)
			(layer "B.SilkS")
		)
		(fp_line
			(start 1.524 -0.762)
			(end -1.524 -0.762)
			(stroke
				(width 0.1524)
				(type default)
			)
			(layer "B.SilkS")
		)
		(fp_line
			(start -1.1049 0.724916)
			(end -1.1049 -0.724916)
			(stroke
				(width 0.1)
				(type default)
			)
			(layer "B.Fab")
		)
		(fp_line
			(start 1.1049 0.724916)
			(end -1.1049 0.724916)
			(stroke
				(width 0.1)
				(type default)
			)
			(layer "B.Fab")
		)
		(fp_line
			(start -1.1049 -0.724916)
			(end 1.1049 -0.724916)
			(stroke
				(width 0.1)
				(type default)
			)
			(layer "B.Fab")
		)
		(fp_line
			(start 1.1049 -0.724916)
			(end 1.1049 0.724916)
			(stroke
				(width 0.1)
				(type default)
			)
			(layer "B.Fab")
		)
		(pad "1" smd rect
			(at 0.889 0 270)
			(size 1.016 1.27)
			(layers "B.Cu" "B.Mask" "B.Paste")
			(net "PVCCFA_EHV_FIVRA_CPU1")
		)
		(pad "2" smd rect
			(at -0.889 0 270)
			(size 1.016 1.27)
			(layers "B.Cu" "B.Mask" "B.Paste")
			(net "GND")
		)
	)
)
